# BASEBOARD_FAB2 (Tioga Pass) — schematic netlist excerpt (pin names and nets, part order shuffled) for the footprints in the layout excerpt that follows; sources: Cadence DE-HDL packaged netlist, KiCad conversion of Wiwynn_Tioga_Pass_MB.brd

R1R20  RES  2.21K 1% CHIP  pkg 0402  page 188 : A = P3V3_STBY ; B = SMB_PCH_MEZZ_LOM1_SCL
R3T13  RES  0.0 5% CHIP  pkg 0402  page 215 : A = P3V3_STBY ; B = VR_PVDDQ_ABC_VDD
R8D25  RES  4.75K 1% CHIP  pkg 0402  page 157 : A = P3V3_STBY ; B = RST_BMC_SRST_R2_N

(kicad_pcb
	(version 20260206)
	(generator "pcbnew")
	(generator_version "10.0")
	(general
		(thickness 1.6)
		(legacy_teardrops no)
	)
	(paper "A4")
	(title_block
		(title "Wiwynn_Tioga_Pass_MB.brd")
		(comment 1 "Tioga Pass / footprints 3462-3464 of 4770")
	)
	(layers
		(0 "F.Cu" signal "TOP")
		(4 "In1.Cu" signal "L2GND")
		(6 "In2.Cu" signal "L3")
		(8 "In3.Cu" signal "L4GND")
		(10 "In4.Cu" signal "L5")
		(12 "In5.Cu" signal "L6GND")
		(14 "In6.Cu" signal "L7VCC")
		(16 "In7.Cu" signal "L8VCC")
		(18 "In8.Cu" signal "L9GND")
		(20 "In9.Cu" signal "L10")
		(22 "In10.Cu" signal "L11GND")
		(24 "In11.Cu" signal "L12")
		(26 "In12.Cu" signal "L13GND")
		(2 "B.Cu" signal "BOTTOM")
		(9 "F.Adhes" user "F.Adhesive")
		(11 "B.Adhes" user "B.Adhesive")
		(13 "F.Paste" user "Package Geometry/Pastemask Top")
		(15 "B.Paste" user "Package Geometry/Pastemask Bottom")
		(5 "F.SilkS" user "Ref Des/Silkscreen Top")
		(7 "B.SilkS" user "Ref Des/Silkscreen Bottom")
		(1 "F.Mask" user "Board Geometry/Soldermask Top")
		(3 "B.Mask" user "Board Geometry/Soldermask Bottom")
		(17 "Dwgs.User" user "User.Drawings")
		(19 "Cmts.User" user "User.Comments")
		(21 "Eco1.User" user "User.Eco1")
		(23 "Eco2.User" user "User.Eco2")
		(25 "Edge.Cuts" user "Board Geometry/Outline")
		(27 "Margin" user)
		(31 "F.CrtYd" user "Package Geometry/Place Bound Top")
		(29 "B.CrtYd" user "Package Geometry/Place Bound Bottom")
		(35 "F.Fab" user "Ref Des/Assembly Top")
		(33 "B.Fab" user "Ref Des/Assembly Bottom")
	)
	(footprint ""
		(layer "B.Cu")
		(at 454.311258 -31.999174 90)
		(property "Reference" "R8D25"
			(at 0 0 90)
			(layer "B.SilkS")
			(hide yes)
			(effects
				(font
					(size 1.27 1.27)
				)
				(justify mirror)
			)
		)
		(property "Value" ""
			(at 0 0 90)
			(layer "B.Fab")
			(effects
				(font
					(size 1.27 1.27)
				)
				(justify mirror)
			)
		)
		(duplicate_pad_numbers_are_jumpers no)
		(fp_poly
			(pts
				(xy 0.2794 -0.1016) (xy -0.2794 -0.1016) (xy -0.2794 0.9906) (xy 0.2794 0.9906)
			)
			(stroke
				(width 0)
				(type default)
			)
			(fill no)
			(layer "B.CrtYd")
		)
		(fp_line
			(start 0.2794 -0.1016)
			(end 0.2794 0.9906)
			(stroke
				(width 0.1)
				(type default)
			)
			(layer "B.Fab")
		)
		(fp_line
			(start -0.2794 -0.1016)
			(end 0.2794 -0.1016)
			(stroke
				(width 0.1)
				(type default)
			)
			(layer "B.Fab")
		)
		(fp_line
			(start 0.2794 0.9906)
			(end -0.2794 0.9906)
			(stroke
				(width 0.1)
				(type default)
			)
			(layer "B.Fab")
		)
		(fp_line
			(start -0.2794 0.9906)
			(end -0.2794 -0.1016)
			(stroke
				(width 0.1)
				(type default)
			)
			(layer "B.Fab")
		)
		(pad "1" smd rect
			(at 0 0 270)
			(size 0.508 0.508)
			(layers "B.Cu" "B.Mask" "B.Paste")
			(net "P3V3_STBY")
		)
		(pad "2" smd rect
			(at 0 0.889 270)
			(size 0.508 0.508)
			(layers "B.Cu" "B.Mask" "B.Paste")
			(net "RST_BMC_SRST_R2_N")
		)
		(zone
			(layer "B.Cu")
			(hatch none 0.5)
			(connect_pads
				(clearance 0)
			)
			(min_thickness 0.25)
			(keepout
				(tracks allowed)
				(vias not_allowed)
				(pads allowed)
				(copperpour not_allowed)
				(footprints allowed)
			)
			(placement
				(enabled no)
				(sheetname "")
			)
			(fill
				(thermal_gap 0.5)
				(thermal_bridge_width 0.5)
				(island_removal_mode 0)
			)
			(polygon
				(pts
					(xy 454.565258 -32.253174) (xy 454.565258 -31.745174) (xy 454.946258 -31.745174) (xy 454.946258 -32.253174)
				)
			)
		)
		(zone
			(layer "B.Cu")
			(hatch none 0.5)
			(connect_pads
				(clearance 0)
			)
			(min_thickness 0.25)
			(keepout
				(tracks not_allowed)
				(vias allowed)
				(pads allowed)
				(copperpour not_allowed)
				(footprints allowed)
			)
			(placement
				(enabled no)
				(sheetname "")
			)
			(fill
				(thermal_gap 0.5)
				(thermal_bridge_width 0.5)
				(island_removal_mode 0)
			)
			(polygon
				(pts
					(xy 454.946258 -32.253174) (xy 454.946258 -31.745174) (xy 454.565258 -31.745174) (xy 454.565258 -32.253174)
				)
			)
		)
	)
	(footprint ""
		(layer "B.Cu")
		(at 349.377 -16.51 180)
		(property "Reference" "R3T13"
			(at 0 0 0)
			(layer "B.SilkS")
			(hide yes)
			(effects
				(font
					(size 1.27 1.27)
				)
				(justify mirror)
			)
		)
		(property "Value" ""
			(at 0 0 0)
			(layer "B.Fab")
			(effects
				(font
					(size 1.27 1.27)
				)
				(justify mirror)
			)
		)
		(duplicate_pad_numbers_are_jumpers no)
		(fp_rect
			(start -0.2794 0.9906)
			(end 0.2794 -0.1016)
			(stroke
				(width 0)
				(type default)
			)
			(fill no)
			(layer "B.CrtYd")
		)
		(fp_line
			(start 0.2794 0.9906)
			(end -0.2794 0.9906)
			(stroke
				(width 0.1)
				(type default)
			)
			(layer "B.Fab")
		)
		(fp_line
			(start 0.2794 -0.1016)
			(end 0.2794 0.9906)
			(stroke
				(width 0.1)
				(type default)
			)
			(layer "B.Fab")
		)
		(fp_line
			(start -0.2794 0.9906)
			(end -0.2794 -0.1016)
			(stroke
				(width 0.1)
				(type default)
			)
			(layer "B.Fab")
		)
		(fp_line
			(start -0.2794 -0.1016)
			(end 0.2794 -0.1016)
			(stroke
				(width 0.1)
				(type default)
			)
			(layer "B.Fab")
		)
		(pad "1" smd rect
			(at 0 0)
			(size 0.508 0.508)
			(layers "B.Cu" "B.Mask" "B.Paste")
			(net "P3V3_STBY")
		)
		(pad "2" smd rect
			(at 0 0.889)
			(size 0.508 0.508)
			(layers "B.Cu" "B.Mask" "B.Paste")
			(net "VR_PVDDQ_ABC_VDD")
		)
		(zone
			(layer "B.Cu")
			(hatch none 0.5)
			(connect_pads
				(clearance 0)
			)
			(min_thickness 0.25)
			(keepout
				(tracks allowed)
				(vias not_allowed)
				(pads allowed)
				(copperpour not_allowed)
				(footprints allowed)
			)
			(placement
				(enabled no)
				(sheetname "")
			)
			(fill
				(thermal_gap 0.5)
				(thermal_bridge_width 0.5)
				(island_removal_mode 0)
			)
			(polygon
				(pts
					(xy 349.631 -17.145) (xy 349.123 -17.145) (xy 349.123 -16.764) (xy 349.631 -16.764)
				)
			)
		)
		(zone
			(layer "B.Cu")
			(hatch none 0.5)
			(connect_pads
				(clearance 0)
			)
			(min_thickness 0.25)
			(keepout
				(tracks not_allowed)
				(vias allowed)
				(pads allowed)
				(copperpour not_allowed)
				(footprints allowed)
			)
			(placement
				(enabled no)
				(sheetname "")
			)
			(fill
				(thermal_gap 0.5)
				(thermal_bridge_width 0.5)
				(island_removal_mode 0)
			)
			(polygon
				(pts
					(xy 349.631 -17.145) (xy 349.123 -17.145) (xy 349.123 -16.764) (xy 349.631 -16.764)
				)
			)
		)
	)
	(footprint ""
		(layer "B.Cu")
		(at 470.027 -57.912 -90)
		(property "Reference" "R1R20"
			(at 0 0 90)
			(layer "B.SilkS")
			(hide yes)
			(effects
				(font
					(size 1.27 1.27)
				)
				(justify mirror)
			)
		)
		(property "Value" ""
			(at 0 0 90)
			(layer "B.Fab")
			(effects
				(font
					(size 1.27 1.27)
				)
				(justify mirror)
			)
		)
		(duplicate_pad_numbers_are_jumpers no)
		(fp_poly
			(pts
				(xy 0.2794 -0.1016) (xy -0.2794 -0.1016) (xy -0.2794 0.9906) (xy 0.2794 0.9906)
			)
			(stroke
				(width 0)
				(type default)
			)
			(fill no)
			(layer "B.CrtYd")
		)
		(fp_line
			(start -0.2794 0.9906)
			(end -0.2794 -0.1016)
			(stroke
				(width 0.1)
				(type default)
			)
			(layer "B.Fab")
		)
		(fp_line
			(start 0.2794 0.9906)
			(end -0.2794 0.9906)
			(stroke
				(width 0.1)
				(type default)
			)
			(layer "B.Fab")
		)
		(fp_line
			(start -0.2794 -0.1016)
			(end 0.2794 -0.1016)
			(stroke
				(width 0.1)
				(type default)
			)
			(layer "B.Fab")
		)
		(fp_line
			(start 0.2794 -0.1016)
			(end 0.2794 0.9906)
			(stroke
				(width 0.1)
				(type default)
			)
			(layer "B.Fab")
		)
		(pad "1" smd rect
			(at 0 0 90)
			(size 0.508 0.508)
			(layers "B.Cu" "B.Mask" "B.Paste")
			(net "P3V3_STBY")
		)
		(pad "2" smd rect
			(at 0 0.889 90)
			(size 0.508 0.508)
			(layers "B.Cu" "B.Mask" "B.Paste")
			(net "SMB_PCH_MEZZ_LOM1_SCL")
		)
		(zone
			(layer "B.Cu")
			(hatch none 0.5)
			(connect_pads
				(clearance 0)
			)
			(min_thickness 0.25)
			(keepout
				(tracks not_allowed)
				(vias allowed)
				(pads allowed)
				(copperpour not_allowed)
				(footprints allowed)
			)
			(placement
				(enabled no)
				(sheetname "")
			)
			(fill
				(thermal_gap 0.5)
				(thermal_bridge_width 0.5)
				(island_removal_mode 0)
			)
			(polygon
				(pts
					(xy 469.392 -57.658) (xy 469.392 -58.166) (xy 469.773 -58.166) (xy 469.773 -57.658)
				)
			)
		)
		(zone
			(layer "B.Cu")
			(hatch none 0.5)
			(connect_pads
				(clearance 0)
			)
			(min_thickness 0.25)
			(keepout
				(tracks allowed)
				(vias not_allowed)
				(pads allowed)
				(copperpour not_allowed)
				(footprints allowed)
			)
			(placement
				(enabled no)
				(sheetname "")
			)
			(fill
				(thermal_gap 0.5)
				(thermal_bridge_width 0.5)
				(island_removal_mode 0)
			)
			(polygon
				(pts
					(xy 469.773 -57.658) (xy 469.773 -58.166) (xy 469.392 -58.166) (xy 469.392 -57.658)
				)
			)
		)
	)
)
